# T6G (Grand Teton) — schematic netlist excerpt (pin names and nets, part order shuffled) for the footprints in the layout excerpt that follows; sources: Cadence DE-HDL packaged netlist, KiCad conversion of 04192023_DAF0TMB3IC0_F0TG_MB_C_brd_V02_OCP.brd

J17  SCONN288_DDR506112002KQ  IO  pkg DDR288S_1-1VXC  page 88
  VIN_BULK0  = P12V_MEM_CPU0
  RFU0  = NC
  VIN_MGMT  = P3V3_AUX
  HSCL  = I3C_SPD_DDRC_CPU0_SCL
  HSDA  = I3C_SPD_DDRC_CPU0_SDA
  VSS0  = GND
  DQ0_A  = M_C_CPU0_SA_DQ<0>
  VSS1  = GND
  DQ1_A  = M_C_CPU0_SA_DQ<1>
  VSS2  = GND
  DQS0_A_T  = M_C_CPU0_SA_DQS_DP<0>
  DQS0_A_C  = M_C_CPU0_SA_DQS_DN<0>
  VSS3  = GND
  DQ4_A  = M_C_CPU0_SA_DQ<4>
  VSS4  = GND
  DQ5_A  = M_C_CPU0_SA_DQ<5>
  VSS5  = GND
  DQ8_A  = M_C_CPU0_SA_DQ<8>
  VSS6  = GND
  DQ9_A  = M_C_CPU0_SA_DQ<9>
  VSS7  = GND
  DQS1_A_T  = M_C_CPU0_SA_DQS_DP<1>
  DQS1_A_C  = M_C_CPU0_SA_DQS_DN<1>
  VSS8  = GND
  DQ12_A  = M_C_CPU0_SA_DQ<12>
  VSS9  = GND
  DQ13_A  = M_C_CPU0_SA_DQ<13>
  VSS10  = GND
  DQ16_A  = M_C_CPU0_SA_DQ<16>
  VSS11  = GND
  DQ17_A  = M_C_CPU0_SA_DQ<17>
  VSS12  = GND
  DQS2_A_T  = M_C_CPU0_SA_DQS_DP<2>
  DQS2_A_C  = M_C_CPU0_SA_DQS_DN<2>
  VSS13  = GND
  DQ20_A  = M_C_CPU0_SA_DQ<20>
  VSS14  = GND
  DQ21_A  = M_C_CPU0_SA_DQ<21>
  VSS15  = GND
  DQ24_A  = M_C_CPU0_SA_DQ<24>
  VSS16  = GND
  DQ25_A  = M_C_CPU0_SA_DQ<25>
  VSS17  = GND
  DQS3_A_T  = M_C_CPU0_SA_DQS_DP<3>
  DQS3_A_C  = M_C_CPU0_SA_DQS_DN<3>
  VSS18  = GND
  DQ28_A  = M_C_CPU0_SA_DQ<28>
  VSS19  = GND
  DQ29_A  = M_C_CPU0_SA_DQ<29>
  VSS20  = GND
  CB0_A  = M_C_CPU0_SA_CB<0>
  VSS21  = GND
  CB1_A  = M_C_CPU0_SA_CB<1>
  VSS22  = GND
  DQS4_A_T  = M_C_CPU0_SA_DQS_DP<4>
  DQS4_A_C  = M_C_CPU0_SA_DQS_DN<4>
  VSS23  = GND
  CB4_A  = M_C_CPU0_SA_CB<4>
  VSS24  = GND
  CB5_A  = M_C_CPU0_SA_CB<5>
  VSS25  = GND
  ALERT_N  = M_C_CPU0_ALERT_N
  VSS26  = GND
  CS0_A_N  = M_C_CPU0_SA_CS_N<0>
  VSS27  = GND
  CA0_A  = M_C_CPU0_SA_CA<0>
  VSS28  = GND
  CA2_A  = M_C_CPU0_SA_CA<2>
  VSS29  = GND
  CA4_A  = M_C_CPU0_SA_CA<4>
  VSS30  = GND
  CA6_A  = M_C_CPU0_SA_CA<6>
  VSS31  = GND
  PAR_A  = M_C_CPU0_SA_PAR
  VSS32  = GND
  CA0_B  = M_C_CPU0_SB_CA<0>
  VSS33  = GND
  CA2_B  = M_C_CPU0_SB_CA<2>
  VSS34  = GND
  CA4_B  = M_C_CPU0_SB_CA<4>
  VSS35  = GND
  CA6_B  = M_C_CPU0_SB_CA<6>
  VSS36  = GND
  CS0_B_N  = M_C_CPU0_SB_CS_N<0>
  VSS37  = GND
  \lbd||rsp_a_n\  = M_C_CPU0_SA_RSP<0>
  \lbs||rsp_b_n\  = M_C_CPU0_SB_RSP<0>
  VSS38  = GND
  CB4_B  = M_C_CPU0_SB_CB<4>
  VSS39  = GND
  CB5_B  = M_C_CPU0_SB_CB<5>
  VSS40  = GND
  \dqs9_b_t||tdqs9_b_t||dbi4_b_n\  = M_C_CPU0_SB_DQS_DP<9>
  \dqs9_b_c||tdqs9_b_c\  = M_C_CPU0_SB_DQS_DN<9>
  VSS41  = GND
  CB0_B  = M_C_CPU0_SB_CB<0>
  VSS42  = GND
  CB1_B  = M_C_CPU0_SB_CB<1>
  VSS43  = GND
  DQ0_B  = M_C_CPU0_SB_DQ<0>
  VSS44  = GND
  DQ1_B  = M_C_CPU0_SB_DQ<1>
  VSS45  = GND
  DQS0_B_T  = M_C_CPU0_SB_DQS_DP<0>
  DQS0_B_C  = M_C_CPU0_SB_DQS_DN<0>
  VSS46  = GND
  DQ4_B  = M_C_CPU0_SB_DQ<4>
  VSS47  = GND
  DQ5_B  = M_C_CPU0_SB_DQ<5>
  VSS48  = GND
  DQ8_B  = M_C_CPU0_SB_DQ<8>
  VSS49  = GND
  DQ9_B  = M_C_CPU0_SB_DQ<9>
  VSS50  = GND
  DQS1_B_T  = M_C_CPU0_SB_DQS_DP<1>
  DQS1_B_C  = M_C_CPU0_SB_DQS_DN<1>
  VSS51  = GND
  DQ12_B  = M_C_CPU0_SB_DQ<12>
  VSS52  = GND
  DQ13_B  = M_C_CPU0_SB_DQ<13>
  VSS53  = GND
  DQ16_B  = M_C_CPU0_SB_DQ<16>
  VSS54  = GND
  DQ17_B  = M_C_CPU0_SB_DQ<17>
  VSS55  = GND
  DQS2_B_T  = M_C_CPU0_SB_DQS_DP<2>
  DQS2_B_C  = M_C_CPU0_SB_DQS_DN<2>
  VSS56  = GND
  DQ20_B  = M_C_CPU0_SB_DQ<20>
  VSS57  = GND
  DQ21_B  = M_C_CPU0_SB_DQ<21>
  VSS58  = GND
  DQ24_B  = M_C_CPU0_SB_DQ<24>
  VSS59  = GND
  DQ25_B  = M_C_CPU0_SB_DQ<25>
  VSS60  = GND
  DQS3_B_T  = M_C_CPU0_SB_DQS_DP<3>
  DQS3_B_C  = M_C_CPU0_SB_DQS_DN<3>
  VSS61  = GND
  DQ28_B  = M_C_CPU0_SB_DQ<28>
  VSS62  = GND
  DQ29_B  = M_C_CPU0_SB_DQ<29>
  VSS63  = GND
  RFU1  = NC
  VIN_BULK1  = P12V_MEM_CPU0
  VIN_BULK2  = P12V_MEM_CPU0
  \pwr_good||fail_n\  = PWRGD_CHC_CPU0_DIMM
  HAS  = PD_CHC_CPU0_DIMM_SAA
  RFU2  = NC
  RFU3  = NC
  VSS64  = GND
  DQ2_A  = M_C_CPU0_SA_DQ<2>
  VSS65  = GND
  DQ3_A  = M_C_CPU0_SA_DQ<3>
  VSS66  = GND
  \dqs5_a_c||tdqs5_a_c||dqs5_a_t||tdqs5_a_t\  = M_C_CPU0_SA_DQS_DN<5>
  \dqs5_a_t||tdqs5_a_t\  = M_C_CPU0_SA_DQS_DP<5>
  VSS67  = GND
  DQ6_A  = M_C_CPU0_SA_DQ<6>
  VSS68  = GND
  DQ7_A  = M_C_CPU0_SA_DQ<7>
  VSS69  = GND
  DQ10_A  = M_C_CPU0_SA_DQ<10>
  VSS70  = GND
  DQ11_A  = M_C_CPU0_SA_DQ<11>
  VSS71  = GND
  \dqs6_a_c||tdqs6_a_c||dqs6_a_t||tdqs6_a_t\  = M_C_CPU0_SA_DQS_DN<6>
  \dqs6_a_t||tdqs6_a_t\  = M_C_CPU0_SA_DQS_DP<6>
  VSS72  = GND
  DQ14_A  = M_C_CPU0_SA_DQ<14>
  VSS73  = GND
  DQ15_A  = M_C_CPU0_SA_DQ<15>
  VSS74  = GND
  DQ18_A  = M_C_CPU0_SA_DQ<18>
  VSS75  = GND
  DQ19_A  = M_C_CPU0_SA_DQ<19>
  VSS76  = GND
  \dqs7_a_c||tdqs7_a_c\  = M_C_CPU0_SA_DQS_DN<7>
  \dqs7_a_t||tdqs7_a_t\  = M_C_CPU0_SA_DQS_DP<7>
  VSS77  = GND
  DQ22_A  = M_C_CPU0_SA_DQ<22>
  VSS78  = GND
  DQ23_A  = M_C_CPU0_SA_DQ<23>
  VSS79  = GND
  DQ26_A  = M_C_CPU0_SA_DQ<26>
  VSS80  = GND
  DQ27_A  = M_C_CPU0_SA_DQ<27>
  VSS81  = GND
  \dqs8_a_c||tdqs8_a_c\  = M_C_CPU0_SA_DQS_DN<8>
  \dqs8_a_t||tdqs8_a_t\  = M_C_CPU0_SA_DQS_DP<8>
  VSS82  = GND
  DQ30_A  = M_C_CPU0_SA_DQ<30>
  VSS83  = GND
  DQ31_A  = M_C_CPU0_SA_DQ<31>
  VSS84  = GND
  CB2_A  = M_C_CPU0_SA_CB<2>
  VSS85  = GND
  CB3_A  = M_C_CPU0_SA_CB<3>
  VSS86  = GND
  \dqs9_a_c||tdqs9_a_c\  = M_C_CPU0_SA_DQS_DN<9>
  \dqs9_a_t||tdqs9_a_t\  = M_C_CPU0_SA_DQS_DP<9>
  VSS87  = GND
  CB6_A  = M_C_CPU0_SA_CB<6>
  VSS88  = GND
  CB7_A  = M_C_CPU0_SA_CB<7>
  VSS89  = GND
  RESET_N  = M_C_CPU0_RESET_N
  VSS90  = GND
  CS1_A_N  = M_C_CPU0_SA_CS_N<1>
  VSS91  = GND
  CA1_A  = M_C_CPU0_SA_CA<1>
  VSS92  = GND
  CA3_A  = M_C_CPU0_SA_CA<3>
  VSS93  = GND
  CA5_A  = M_C_CPU0_SA_CA<5>
  VSS94  = GND
  CK_T  = M_C_CPU0_CLK_DP<0>
  CK_C  = M_C_CPU0_CLK_DN<0>
  VSS95  = GND
  RFU4  = NC
  CA1_B  = M_C_CPU0_SB_CA<1>
  VSS96  = GND
  CA3_B  = M_C_CPU0_SB_CA<3>
  VSS97  = GND
  CA5_B  = M_C_CPU0_SB_CA<5>
  VSS98  = GND
  PAR_B  = M_C_CPU0_SB_PAR
  VSS99  = GND
  CS1_B_N  = M_C_CPU0_SB_CS_N<1>
  VSS100  = GND
  RFU5  = NC
  RFU6  = NC
  VSS101  = GND
  CB6_B  = M_C_CPU0_SB_CB<6>
  VSS102  = GND
  CB7_B  = M_C_CPU0_SB_CB<7>
  VSS103  = GND
  DQS4_B_C  = M_C_CPU0_SB_DQS_DN<4>
  DQS4_B_T  = M_C_CPU0_SB_DQS_DP<4>
  VSS104  = GND
  CB2_B  = M_C_CPU0_SB_CB<2>
  VSS105  = GND
  CB3_B  = M_C_CPU0_SB_CB<3>
  VSS106  = GND
  DQ2_B  = M_C_CPU0_SB_DQ<2>
  VSS107  = GND
  DQ3_B  = M_C_CPU0_SB_DQ<3>
  VSS108  = GND
  \dqs5_b_c||tdqs5_b_c\  = M_C_CPU0_SB_DQS_DN<5>
  \dqs5_b_t||tdqs5_b_t\  = M_C_CPU0_SB_DQS_DP<5>
  VSS109  = GND
  DQ6_B  = M_C_CPU0_SB_DQ<6>
  VSS110  = GND
  DQ7_B  = M_C_CPU0_SB_DQ<7>
  VSS111  = GND
  DQ10_B  = M_C_CPU0_SB_DQ<10>
  VSS112  = GND
  DQ11_B  = M_C_CPU0_SB_DQ<11>
  VSS113  = GND
  \dqs6_b_c||tdqs6_b_c\  = M_C_CPU0_SB_DQS_DN<6>
  \dqs6_b_t||tdqs6_b_t\  = M_C_CPU0_SB_DQS_DP<6>
  VSS114  = GND
  DQ14_B  = M_C_CPU0_SB_DQ<14>
  VSS115  = GND
  DQ15_B  = M_C_CPU0_SB_DQ<15>
  VSS116  = GND
  DQ18_B  = M_C_CPU0_SB_DQ<18>
  VSS117  = GND
  DQ19_B  = M_C_CPU0_SB_DQ<19>
  VSS118  = GND
  \dqs7_b_c||tdqs7_b_c\  = M_C_CPU0_SB_DQS_DN<7>
  \dqs7_b_t||tdqs7_b_t\  = M_C_CPU0_SB_DQS_DP<7>
  VSS119  = GND
  DQ22_B  = M_C_CPU0_SB_DQ<22>
  VSS120  = GND
  DQ23_B  = M_C_CPU0_SB_DQ<23>
  VSS121  = GND
  DQ26_B  = M_C_CPU0_SB_DQ<26>
  VSS122  = GND
  DQ27_B  = M_C_CPU0_SB_DQ<27>
  VSS123  = GND
  \dqs8_b_c||tdqs8_b_c\  = M_C_CPU0_SB_DQS_DN<8>
  \dqs8_b_t||tdqs8_b_t\  = M_C_CPU0_SB_DQS_DP<8>
  VSS124  = GND
  DQ30_B  = M_C_CPU0_SB_DQ<30>
  VSS125  = GND
  DQ31_B  = M_C_CPU0_SB_DQ<31>
  VSS126  = GND
  G1  = GND
  G2  = GND
  G3  = GND

(kicad_pcb
	(version 20260206)
	(generator "pcbnew")
	(generator_version "10.0")
	(general
		(thickness 1.6)
		(legacy_teardrops no)
	)
	(paper "A4")
	(title_block
		(title "04192023_DAF0TMB3IC0_F0TG_MB_C_brd_V02_OCP.brd")
		(comment 1 "Grand Teton / footprint 4167 of 8354 (J17), pads 185-230 of 291")
	)
	(layers
		(0 "F.Cu" signal "TOP")
		(4 "In1.Cu" signal "GND")
		(6 "In2.Cu" signal "IN1")
		(8 "In3.Cu" signal "GND1")
		(10 "In4.Cu" signal "IN2")
		(12 "In5.Cu" signal "GND2")
		(14 "In6.Cu" signal "IN3")
		(16 "In7.Cu" signal "GND3")
		(18 "In8.Cu" signal "VCC")
		(20 "In9.Cu" signal "VCC1")
		(22 "In10.Cu" signal "GND4")
		(24 "In11.Cu" signal "IN4")
		(26 "In12.Cu" signal "GND5")
		(28 "In13.Cu" signal "IN5")
		(30 "In14.Cu" signal "GND6")
		(32 "In15.Cu" signal "IN6")
		(34 "In16.Cu" signal "GND7")
		(2 "B.Cu" signal "BOTTOM")
		(9 "F.Adhes" user "F.Adhesive")
		(11 "B.Adhes" user "B.Adhesive")
		(13 "F.Paste" user "Package Geometry/Pastemask Top")
		(15 "B.Paste" user "Package Geometry/Pastemask Bottom")
		(5 "F.SilkS" user "Ref Des/Silkscreen Top")
		(7 "B.SilkS" user "Ref Des/Silkscreen Bottom")
		(1 "F.Mask" user "Board Geometry/Soldermask Top")
		(3 "B.Mask" user "Board Geometry/Soldermask Bottom")
		(17 "Dwgs.User" user "User.Drawings")
		(19 "Cmts.User" user "User.Comments")
		(21 "Eco1.User" user "User.Eco1")
		(23 "Eco2.User" user "User.Eco2")
		(25 "Edge.Cuts" user "Board Geometry/Outline")
		(27 "Margin" user)
		(31 "F.CrtYd" user "Package Geometry/Place Bound Top")
		(29 "B.CrtYd" user "Package Geometry/Place Bound Bottom")
		(35 "F.Fab" user "Ref Des/Assembly Top")
		(33 "B.Fab" user "Ref Des/Assembly Bottom")
	)
	(footprint ""
		(layer "F.Cu")
		(at 290.230052 -255.560068 180)
		(property "Reference" "J17"
			(at -2.2098 -81.984088 0)
			(unlocked yes)
			(layer "F.SilkS")
			(effects
				(font
					(size 0.7874 0.5842)
					(thickness 0.1524)
				)
			)
		)
		(property "Value" ""
			(at 0 0 180)
			(layer "F.Fab")
			(effects
				(font
					(size 1.27 1.27)
				)
			)
		)
		(duplicate_pad_numbers_are_jumpers no)
		(pad "185" smd rect
			(at 2.050034 -29.325062 90)
			(size 0.519938 1.4986)
			(layers "F.Cu" "F.Mask" "F.Paste")
			(net "M_C_CPU0_SA_DQ<26>")
		)
		(pad "186" smd rect
			(at 2.050034 -28.474924 90)
			(size 0.519938 1.4986)
			(layers "F.Cu" "F.Mask" "F.Paste")
			(net "GND")
		)
		(pad "187" smd rect
			(at 2.050034 -27.62504 90)
			(size 0.519938 1.4986)
			(layers "F.Cu" "F.Mask" "F.Paste")
			(net "M_C_CPU0_SA_DQ<27>")
		)
		(pad "188" smd rect
			(at 2.050034 -26.774902 90)
			(size 0.519938 1.4986)
			(layers "F.Cu" "F.Mask" "F.Paste")
			(net "GND")
		)
		(pad "189" smd rect
			(at 2.050034 -25.925018 90)
			(size 0.519938 1.4986)
			(layers "F.Cu" "F.Mask" "F.Paste")
			(net "M_C_CPU0_SA_DQS_DN<8>")
		)
		(pad "190" smd rect
			(at 2.050034 -25.07488 90)
			(size 0.519938 1.4986)
			(layers "F.Cu" "F.Mask" "F.Paste")
			(net "M_C_CPU0_SA_DQS_DP<8>")
		)
		(pad "191" smd rect
			(at 2.050034 -24.224996 90)
			(size 0.519938 1.4986)
			(layers "F.Cu" "F.Mask" "F.Paste")
			(net "GND")
		)
		(pad "192" smd rect
			(at 2.050034 -23.375112 90)
			(size 0.519938 1.4986)
			(layers "F.Cu" "F.Mask" "F.Paste")
			(net "M_C_CPU0_SA_DQ<30>")
		)
		(pad "193" smd rect
			(at 2.050034 -22.524974 90)
			(size 0.519938 1.4986)
			(layers "F.Cu" "F.Mask" "F.Paste")
			(net "GND")
		)
		(pad "194" smd rect
			(at 2.050034 -21.67509 90)
			(size 0.519938 1.4986)
			(layers "F.Cu" "F.Mask" "F.Paste")
			(net "M_C_CPU0_SA_DQ<31>")
		)
		(pad "195" smd rect
			(at 2.050034 -20.824952 90)
			(size 0.519938 1.4986)
			(layers "F.Cu" "F.Mask" "F.Paste")
			(net "GND")
		)
		(pad "196" smd rect
			(at 2.050034 -19.975068 90)
			(size 0.519938 1.4986)
			(layers "F.Cu" "F.Mask" "F.Paste")
			(net "M_C_CPU0_SA_CB<2>")
		)
		(pad "197" smd rect
			(at 2.050034 -19.12493 90)
			(size 0.519938 1.4986)
			(layers "F.Cu" "F.Mask" "F.Paste")
			(net "GND")
		)
		(pad "198" smd rect
			(at 2.050034 -18.275046 90)
			(size 0.519938 1.4986)
			(layers "F.Cu" "F.Mask" "F.Paste")
			(net "M_C_CPU0_SA_CB<3>")
		)
		(pad "199" smd rect
			(at 2.050034 -17.424908 90)
			(size 0.519938 1.4986)
			(layers "F.Cu" "F.Mask" "F.Paste")
			(net "GND")
		)
		(pad "200" smd rect
			(at 2.050034 -16.575024 90)
			(size 0.519938 1.4986)
			(layers "F.Cu" "F.Mask" "F.Paste")
			(net "M_C_CPU0_SA_DQS_DN<9>")
		)
		(pad "201" smd rect
			(at 2.050034 -15.724886 90)
			(size 0.519938 1.4986)
			(layers "F.Cu" "F.Mask" "F.Paste")
			(net "M_C_CPU0_SA_DQS_DP<9>")
		)
		(pad "202" smd rect
			(at 2.050034 -14.875002 90)
			(size 0.519938 1.4986)
			(layers "F.Cu" "F.Mask" "F.Paste")
			(net "GND")
		)
		(pad "203" smd rect
			(at 2.050034 -14.025118 90)
			(size 0.519938 1.4986)
			(layers "F.Cu" "F.Mask" "F.Paste")
			(net "M_C_CPU0_SA_CB<6>")
		)
		(pad "204" smd rect
			(at 2.050034 -13.17498 90)
			(size 0.519938 1.4986)
			(layers "F.Cu" "F.Mask" "F.Paste")
			(net "GND")
		)
		(pad "205" smd rect
			(at 2.050034 -12.325096 90)
			(size 0.519938 1.4986)
			(layers "F.Cu" "F.Mask" "F.Paste")
			(net "M_C_CPU0_SA_CB<7>")
		)
		(pad "206" smd rect
			(at 2.050034 -11.474958 90)
			(size 0.519938 1.4986)
			(layers "F.Cu" "F.Mask" "F.Paste")
			(net "GND")
		)
		(pad "207" smd rect
			(at 2.050034 -10.625074 90)
			(size 0.519938 1.4986)
			(layers "F.Cu" "F.Mask" "F.Paste")
			(net "M_C_CPU0_RESET_N")
		)
		(pad "208" smd rect
			(at 2.050034 -9.774936 90)
			(size 0.519938 1.4986)
			(layers "F.Cu" "F.Mask" "F.Paste")
			(net "GND")
		)
		(pad "209" smd rect
			(at 2.050034 -8.925052 90)
			(size 0.519938 1.4986)
			(layers "F.Cu" "F.Mask" "F.Paste")
			(net "M_C_CPU0_SA_CS_N<1>")
		)
		(pad "210" smd rect
			(at 2.050034 -8.074914 90)
			(size 0.519938 1.4986)
			(layers "F.Cu" "F.Mask" "F.Paste")
			(net "GND")
		)
		(pad "211" smd rect
			(at 2.050034 -7.22503 90)
			(size 0.519938 1.4986)
			(layers "F.Cu" "F.Mask" "F.Paste")
			(net "M_C_CPU0_SA_CA<1>")
		)
		(pad "212" smd rect
			(at 2.050034 -6.374892 90)
			(size 0.519938 1.4986)
			(layers "F.Cu" "F.Mask" "F.Paste")
			(net "GND")
		)
		(pad "213" smd rect
			(at 2.050034 -5.525008 90)
			(size 0.519938 1.4986)
			(layers "F.Cu" "F.Mask" "F.Paste")
			(net "M_C_CPU0_SA_CA<3>")
		)
		(pad "214" smd rect
			(at 2.050034 -4.675124 90)
			(size 0.519938 1.4986)
			(layers "F.Cu" "F.Mask" "F.Paste")
			(net "GND")
		)
		(pad "215" smd rect
			(at 2.050034 -3.824986 90)
			(size 0.519938 1.4986)
			(layers "F.Cu" "F.Mask" "F.Paste")
			(net "M_C_CPU0_SA_CA<5>")
		)
		(pad "216" smd rect
			(at 2.050034 -2.975102 90)
			(size 0.519938 1.4986)
			(layers "F.Cu" "F.Mask" "F.Paste")
			(net "GND")
		)
		(pad "217" smd rect
			(at 2.050034 -2.124964 90)
			(size 0.519938 1.4986)
			(layers "F.Cu" "F.Mask" "F.Paste")
			(net "M_C_CPU0_CLK_DP<0>")
		)
		(pad "218" smd rect
			(at 2.050034 -1.27508 90)
			(size 0.519938 1.4986)
			(layers "F.Cu" "F.Mask" "F.Paste")
			(net "M_C_CPU0_CLK_DN<0>")
		)
		(pad "219" smd rect
			(at 2.050034 -0.424942 90)
			(size 0.519938 1.4986)
			(layers "F.Cu" "F.Mask" "F.Paste")
			(net "GND")
		)
		(pad "220" smd rect
			(at 2.050034 5.525008 90)
			(size 0.519938 1.4986)
			(layers "F.Cu" "F.Mask" "F.Paste")
			(net "Net_2281")
		)
		(pad "221" smd rect
			(at 2.050034 6.374892 90)
			(size 0.519938 1.4986)
			(layers "F.Cu" "F.Mask" "F.Paste")
			(net "M_C_CPU0_SB_CA<1>")
		)
		(pad "222" smd rect
			(at 2.050034 7.22503 90)
			(size 0.519938 1.4986)
			(layers "F.Cu" "F.Mask" "F.Paste")
			(net "GND")
		)
		(pad "223" smd rect
			(at 2.050034 8.074914 90)
			(size 0.519938 1.4986)
			(layers "F.Cu" "F.Mask" "F.Paste")
			(net "M_C_CPU0_SB_CA<3>")
		)
		(pad "224" smd rect
			(at 2.050034 8.925052 90)
			(size 0.519938 1.4986)
			(layers "F.Cu" "F.Mask" "F.Paste")
			(net "GND")
		)
		(pad "225" smd rect
			(at 2.050034 9.774936 90)
			(size 0.519938 1.4986)
			(layers "F.Cu" "F.Mask" "F.Paste")
			(net "M_C_CPU0_SB_CA<5>")
		)
		(pad "226" smd rect
			(at 2.050034 10.625074 90)
			(size 0.519938 1.4986)
			(layers "F.Cu" "F.Mask" "F.Paste")
			(net "GND")
		)
		(pad "227" smd rect
			(at 2.050034 11.474958 90)
			(size 0.519938 1.4986)
			(layers "F.Cu" "F.Mask" "F.Paste")
			(net "M_C_CPU0_SB_PAR")
		)
		(pad "228" smd rect
			(at 2.050034 12.325096 90)
			(size 0.519938 1.4986)
			(layers "F.Cu" "F.Mask" "F.Paste")
			(net "GND")
		)
		(pad "229" smd rect
			(at 2.050034 13.17498 90)
			(size 0.519938 1.4986)
			(layers "F.Cu" "F.Mask" "F.Paste")
			(net "M_C_CPU0_SB_CS_N<1>")
		)
		(pad "230" smd rect
			(at 2.050034 14.025118 90)
			(size 0.519938 1.4986)
			(layers "F.Cu" "F.Mask" "F.Paste")
			(net "GND")
		)
	)
)
